(kicad_pcb
	(version 20221018)
	(generator pcbnew)
	(general
    (thickness 1.518)
  )
	(paper "A4")
	(title_block
    (title "Kria K26 Devboard")
    (date "2024-03-26")
    (rev "1.2.5")
    (comment 1 "www.antmicro.com")
    (comment 2 "Antmicro Ltd.")
		(comment 9 "footprints 77-77 of 660")
	)
	(layers
    (0 "F.Cu" mixed)
    (1 "In1.Cu" power)
    (2 "In2.Cu" mixed)
    (3 "In3.Cu" power)
    (4 "In4.Cu" mixed)
    (5 "In5.Cu" power)
    (6 "In6.Cu" mixed)
    (31 "B.Cu" power)
    (32 "B.Adhes" user "B.Adhesive")
    (33 "F.Adhes" user "F.Adhesive")
    (34 "B.Paste" user)
    (35 "F.Paste" user)
    (36 "B.SilkS" user "B.Silkscreen")
    (37 "F.SilkS" user "F.Silkscreen")
    (38 "B.Mask" user)
    (39 "F.Mask" user)
    (40 "Dwgs.User" user "User.Drawings")
    (41 "Cmts.User" user "User.Comments")
    (42 "Eco1.User" user "User.Eco1")
    (43 "Eco2.User" user "User.Eco2")
    (44 "Edge.Cuts" user)
    (45 "Margin" user)
    (46 "B.CrtYd" user "B.Courtyard")
    (47 "F.CrtYd" user "F.Courtyard")
    (48 "B.Fab" user)
    (49 "F.Fab" user)
  )
	(footprint "kria-k26-devboard-footprints:C_0603_1608Metric" (layer "F.Cu")
    (at 125.05 113.2)
    (descr "Capacitor SMD 0603")
    (tags "capacitor 0603")
    (property "Author" "Antmicro")
    (property "License" "Apache-2.0")
    (property "MPN" "GRM188R61A106KE69D")
    (property "Manufacturer" "Murata")
    (property "Sheetfile" "pcie-m2-key-e.kicad_sch")
    (property "Sheetname" "PCIE M2 key E ")
    (property "Val" "10u")
    (property "Voltage" "")
    (property "ki_description" " ")
    (attr smd)
    (fp_text reference "C238" (at -1.63 -0.59) (layer "F.SilkS")
        (effects (font (size 0.7 0.7) (thickness 0.15)) (justify left bottom))
    )
    (fp_text value "C_10u_0603" (at 0 1.6) (layer "F.Fab") hide
        (effects (font (size 0.7 0.7) (thickness 0.15)) (justify left bottom))
    )
    (fp_text user "License: Apache-2.0" (at -1.682 5.895) (layer "F.Fab") hide
        (effects (font (size 0.7 0.7) (thickness 0.15)) (justify left bottom))
    )
    (fp_text user "${REFERENCE}" (at -1.682 3.895) (layer "F.Fab") hide
        (effects (font (size 0.7 0.7) (thickness 0.15)) (justify left bottom))
    )
    (fp_text user "Author: Antmicro" (at -1.682 4.894) (layer "F.Fab") hide
        (effects (font (size 0.7 0.7) (thickness 0.15)) (justify left bottom))
    )
    (fp_line (start -0.3 -0.3) (end 0.3 -0.3)
      (stroke (width 0.15) (type solid)) (layer "F.SilkS"))
    (fp_line (start -0.3 0.3) (end 0.3 0.3)
      (stroke (width 0.15) (type solid)) (layer "F.SilkS"))
    (fp_rect (start -1.24 -0.7) (end 1.24 0.7)
      (stroke (width 0.05) (type solid)) (fill none) (layer "F.CrtYd"))
    (fp_rect (start -0.8 -0.4) (end 0.8 0.4)
      (stroke (width 0.15) (type solid)) (fill none) (layer "F.Fab"))
    (pad "1" smd roundrect (at -0.7 0) (size 0.6 0.8) (layers "F.Cu" "F.Paste" "F.Mask") (roundrect_rratio 0.2)
      (net 15 "PS_3V3") (pintype "passive"))
    (pad "2" smd roundrect (at 0.7 0) (size 0.6 0.8) (layers "F.Cu" "F.Paste" "F.Mask") (roundrect_rratio 0.2)
      (net 1 "GND") (pintype "passive"))
  )
)
